(kicad_pcb
	(version 20260206)
	(generator "pcbnew")
	(generator_version "10.0")
	(general
		(thickness 1.6)
		(legacy_teardrops no)
	)
	(paper "A4")
	(title_block
		(title "12092022_DA0F0TFB6D0_F0T_FAN_BOARD_MP5048_D_brd_v02_OCP.brd")
		(comment 1 "Grand Teton / footprints 897-903 of 924")
	)
	(layers
		(0 "F.Cu" signal "TOP")
		(4 "In1.Cu" signal "GND")
		(6 "In2.Cu" signal "IN1")
		(8 "In3.Cu" signal "IN2")
		(10 "In4.Cu" signal "GND1")
		(2 "B.Cu" signal "BOTTOM")
		(9 "F.Adhes" user "F.Adhesive")
		(11 "B.Adhes" user "B.Adhesive")
		(13 "F.Paste" user "Package Geometry/Pastemask Top")
		(15 "B.Paste" user "Package Geometry/Pastemask Bottom")
		(5 "F.SilkS" user "Ref Des/Silkscreen Top")
		(7 "B.SilkS" user "Ref Des/Silkscreen Bottom")
		(1 "F.Mask" user "Board Geometry/Soldermask Top")
		(3 "B.Mask" user "Board Geometry/Soldermask Bottom")
		(17 "Dwgs.User" user "User.Drawings")
		(19 "Cmts.User" user "User.Comments")
		(21 "Eco1.User" user "User.Eco1")
		(23 "Eco2.User" user "User.Eco2")
		(25 "Edge.Cuts" user "Board Geometry/Outline")
		(27 "Margin" user)
		(31 "F.CrtYd" user "Package Geometry/Place Bound Top")
		(29 "B.CrtYd" user "Package Geometry/Place Bound Bottom")
		(35 "F.Fab" user "Ref Des/Assembly Top")
		(33 "B.Fab" user "Ref Des/Assembly Bottom")
	)
	(footprint ""
		(layer "B.Cu")
		(at 41.746932 -60.382912 -90)
		(property "Reference" "PC60"
			(at 0 0 90)
			(layer "B.SilkS")
			(hide yes)
			(effects
				(font
					(size 1.27 1.27)
				)
				(justify mirror)
			)
		)
		(property "Value" ""
			(at 0 0 90)
			(layer "B.Fab")
			(effects
				(font
					(size 1.27 1.27)
				)
				(justify mirror)
			)
		)
		(duplicate_pad_numbers_are_jumpers no)
		(fp_line
			(start -1.524 0.762)
			(end 1.524 0.762)
			(stroke
				(width 0.1524)
				(type default)
			)
			(layer "B.SilkS")
		)
		(fp_line
			(start 1.524 0.762)
			(end 1.524 -0.762)
			(stroke
				(width 0.1524)
				(type default)
			)
			(layer "B.SilkS")
		)
		(fp_line
			(start -1.524 -0.762)
			(end -1.524 0.762)
			(stroke
				(width 0.1524)
				(type default)
			)
			(layer "B.SilkS")
		)
		(fp_line
			(start 1.524 -0.762)
			(end -1.524 -0.762)
			(stroke
				(width 0.1524)
				(type default)
			)
			(layer "B.SilkS")
		)
		(fp_line
			(start -1.1049 0.724916)
			(end -1.1049 -0.724916)
			(stroke
				(width 0.1)
				(type default)
			)
			(layer "B.Fab")
		)
		(fp_line
			(start 1.1049 0.724916)
			(end -1.1049 0.724916)
			(stroke
				(width 0.1)
				(type default)
			)
			(layer "B.Fab")
		)
		(fp_line
			(start -1.1049 -0.724916)
			(end 1.1049 -0.724916)
			(stroke
				(width 0.1)
				(type default)
			)
			(layer "B.Fab")
		)
		(fp_line
			(start 1.1049 -0.724916)
			(end 1.1049 0.724916)
			(stroke
				(width 0.1)
				(type default)
			)
			(layer "B.Fab")
		)
		(pad "1" smd rect
			(at 0.889 0 270)
			(size 1.016 1.27)
			(layers "B.Cu" "B.Mask" "B.Paste")
			(net "P52V_HSC")
		)
		(pad "2" smd rect
			(at -0.889 0 270)
			(size 1.016 1.27)
			(layers "B.Cu" "B.Mask" "B.Paste")
			(net "GND")
		)
	)
	(footprint ""
		(layer "B.Cu")
		(at 16.129 -73.971912 90)
		(property "Reference" "PC47"
			(at 0 0 90)
			(layer "B.SilkS")
			(hide yes)
			(effects
				(font
					(size 1.27 1.27)
				)
				(justify mirror)
			)
		)
		(property "Value" ""
			(at 0 0 90)
			(layer "B.Fab")
			(effects
				(font
					(size 1.27 1.27)
				)
				(justify mirror)
			)
		)
		(duplicate_pad_numbers_are_jumpers no)
		(fp_line
			(start 0.7874 -0.4064)
			(end -0.7874 -0.4064)
			(stroke
				(width 0.1524)
				(type default)
			)
			(layer "B.SilkS")
		)
		(fp_line
			(start -0.7874 -0.4064)
			(end -0.7874 0.4064)
			(stroke
				(width 0.1524)
				(type default)
			)
			(layer "B.SilkS")
		)
		(fp_line
			(start 0.7874 0.4064)
			(end 0.7874 -0.4064)
			(stroke
				(width 0.1524)
				(type default)
			)
			(layer "B.SilkS")
		)
		(fp_line
			(start -0.7874 0.4064)
			(end 0.7874 0.4064)
			(stroke
				(width 0.1524)
				(type default)
			)
			(layer "B.SilkS")
		)
		(fp_line
			(start 0.67945 -0.305054)
			(end 0.12065 -0.305054)
			(stroke
				(width 0.1)
				(type default)
			)
			(layer "B.Fab")
		)
		(fp_line
			(start 0.12065 -0.305054)
			(end 0.12065 -0.2794)
			(stroke
				(width 0.1)
				(type default)
			)
			(layer "B.Fab")
		)
		(fp_line
			(start -0.12065 -0.3048)
			(end -0.67945 -0.3048)
			(stroke
				(width 0.1)
				(type default)
			)
			(layer "B.Fab")
		)
		(fp_line
			(start -0.67945 -0.3048)
			(end -0.67945 0.3048)
			(stroke
				(width 0.1)
				(type default)
			)
			(layer "B.Fab")
		)
		(fp_line
			(start 0.12065 -0.2794)
			(end -0.12065 -0.2794)
			(stroke
				(width 0.1)
				(type default)
			)
			(layer "B.Fab")
		)
		(fp_line
			(start -0.12065 -0.2794)
			(end -0.12065 -0.3048)
			(stroke
				(width 0.1)
				(type default)
			)
			(layer "B.Fab")
		)
		(fp_line
			(start 0.12065 0.2794)
			(end 0.12065 0.3048)
			(stroke
				(width 0.1)
				(type default)
			)
			(layer "B.Fab")
		)
		(fp_line
			(start -0.120396 0.2794)
			(end 0.12065 0.2794)
			(stroke
				(width 0.1)
				(type default)
			)
			(layer "B.Fab")
		)
		(fp_line
			(start 0.67945 0.3048)
			(end 0.67945 -0.305054)
			(stroke
				(width 0.1)
				(type default)
			)
			(layer "B.Fab")
		)
		(fp_line
			(start 0.12065 0.3048)
			(end 0.67945 0.3048)
			(stroke
				(width 0.1)
				(type default)
			)
			(layer "B.Fab")
		)
		(fp_line
			(start -0.120396 0.3048)
			(end -0.120396 0.2794)
			(stroke
				(width 0.1)
				(type default)
			)
			(layer "B.Fab")
		)
		(fp_line
			(start -0.67945 0.3048)
			(end -0.120396 0.3048)
			(stroke
				(width 0.1)
				(type default)
			)
			(layer "B.Fab")
		)
		(pad "1" smd circle
			(at 0.40005 0 270)
			(size 0 0)
			(layers "B.Cu" "B.Mask" "B.Paste")
			(net "FAN_5_TIMER")
		)
		(pad "2" smd circle
			(at -0.40005 0 270)
			(size 0 0)
			(layers "B.Cu" "B.Mask" "B.Paste")
			(net "GND")
		)
	)
	(footprint ""
		(layer "B.Cu")
		(at 39.47668 -258.562856 90)
		(property "Reference" "PC4"
			(at 0 0 90)
			(layer "B.SilkS")
			(hide yes)
			(effects
				(font
					(size 1.27 1.27)
				)
				(justify mirror)
			)
		)
		(property "Value" ""
			(at 0 0 90)
			(layer "B.Fab")
			(effects
				(font
					(size 1.27 1.27)
				)
				(justify mirror)
			)
		)
		(duplicate_pad_numbers_are_jumpers no)
		(fp_line
			(start 0.7874 -0.4064)
			(end -0.7874 -0.4064)
			(stroke
				(width 0.1524)
				(type default)
			)
			(layer "B.SilkS")
		)
		(fp_line
			(start -0.7874 -0.4064)
			(end -0.7874 0.4064)
			(stroke
				(width 0.1524)
				(type default)
			)
			(layer "B.SilkS")
		)
		(fp_line
			(start 0.7874 0.4064)
			(end 0.7874 -0.4064)
			(stroke
				(width 0.1524)
				(type default)
			)
			(layer "B.SilkS")
		)
		(fp_line
			(start -0.7874 0.4064)
			(end 0.7874 0.4064)
			(stroke
				(width 0.1524)
				(type default)
			)
			(layer "B.SilkS")
		)
		(fp_line
			(start 0.67945 -0.305054)
			(end 0.12065 -0.305054)
			(stroke
				(width 0.1)
				(type default)
			)
			(layer "B.Fab")
		)
		(fp_line
			(start 0.12065 -0.305054)
			(end 0.12065 -0.2794)
			(stroke
				(width 0.1)
				(type default)
			)
			(layer "B.Fab")
		)
		(fp_line
			(start -0.12065 -0.3048)
			(end -0.67945 -0.3048)
			(stroke
				(width 0.1)
				(type default)
			)
			(layer "B.Fab")
		)
		(fp_line
			(start -0.67945 -0.3048)
			(end -0.67945 0.3048)
			(stroke
				(width 0.1)
				(type default)
			)
			(layer "B.Fab")
		)
		(fp_line
			(start 0.12065 -0.2794)
			(end -0.12065 -0.2794)
			(stroke
				(width 0.1)
				(type default)
			)
			(layer "B.Fab")
		)
		(fp_line
			(start -0.12065 -0.2794)
			(end -0.12065 -0.3048)
			(stroke
				(width 0.1)
				(type default)
			)
			(layer "B.Fab")
		)
		(fp_line
			(start 0.12065 0.2794)
			(end 0.12065 0.3048)
			(stroke
				(width 0.1)
				(type default)
			)
			(layer "B.Fab")
		)
		(fp_line
			(start -0.120396 0.2794)
			(end 0.12065 0.2794)
			(stroke
				(width 0.1)
				(type default)
			)
			(layer "B.Fab")
		)
		(fp_line
			(start 0.67945 0.3048)
			(end 0.67945 -0.305054)
			(stroke
				(width 0.1)
				(type default)
			)
			(layer "B.Fab")
		)
		(fp_line
			(start 0.12065 0.3048)
			(end 0.67945 0.3048)
			(stroke
				(width 0.1)
				(type default)
			)
			(layer "B.Fab")
		)
		(fp_line
			(start -0.120396 0.3048)
			(end -0.120396 0.2794)
			(stroke
				(width 0.1)
				(type default)
			)
			(layer "B.Fab")
		)
		(fp_line
			(start -0.67945 0.3048)
			(end -0.120396 0.3048)
			(stroke
				(width 0.1)
				(type default)
			)
			(layer "B.Fab")
		)
		(pad "1" smd circle
			(at 0.40005 0 270)
			(size 0 0)
			(layers "B.Cu" "B.Mask" "B.Paste")
			(net "FAN_0_P5V")
		)
		(pad "2" smd circle
			(at -0.40005 0 270)
			(size 0 0)
			(layers "B.Cu" "B.Mask" "B.Paste")
			(net "GND")
		)
	)
	(footprint ""
		(layer "B.Cu")
		(at 10.380218 -245.3132 -90)
		(property "Reference" "PC63"
			(at 0 0 90)
			(layer "B.SilkS")
			(hide yes)
			(effects
				(font
					(size 1.27 1.27)
				)
				(justify mirror)
			)
		)
		(property "Value" ""
			(at 0 0 90)
			(layer "B.Fab")
			(effects
				(font
					(size 1.27 1.27)
				)
				(justify mirror)
			)
		)
		(duplicate_pad_numbers_are_jumpers no)
		(fp_line
			(start -1.524 0.762)
			(end 1.524 0.762)
			(stroke
				(width 0.1524)
				(type default)
			)
			(layer "B.SilkS")
		)
		(fp_line
			(start 1.524 0.762)
			(end 1.524 -0.762)
			(stroke
				(width 0.1524)
				(type default)
			)
			(layer "B.SilkS")
		)
		(fp_line
			(start -1.524 -0.762)
			(end -1.524 0.762)
			(stroke
				(width 0.1524)
				(type default)
			)
			(layer "B.SilkS")
		)
		(fp_line
			(start 1.524 -0.762)
			(end -1.524 -0.762)
			(stroke
				(width 0.1524)
				(type default)
			)
			(layer "B.SilkS")
		)
		(fp_line
			(start -1.1049 0.724916)
			(end -1.1049 -0.724916)
			(stroke
				(width 0.1)
				(type default)
			)
			(layer "B.Fab")
		)
		(fp_line
			(start 1.1049 0.724916)
			(end -1.1049 0.724916)
			(stroke
				(width 0.1)
				(type default)
			)
			(layer "B.Fab")
		)
		(fp_line
			(start -1.1049 -0.724916)
			(end 1.1049 -0.724916)
			(stroke
				(width 0.1)
				(type default)
			)
			(layer "B.Fab")
		)
		(fp_line
			(start 1.1049 -0.724916)
			(end 1.1049 0.724916)
			(stroke
				(width 0.1)
				(type default)
			)
			(layer "B.Fab")
		)
		(pad "1" smd rect
			(at 0.889 0 270)
			(size 1.016 1.27)
			(layers "B.Cu" "B.Mask" "B.Paste")
			(net "P52V_HSC")
		)
		(pad "2" smd rect
			(at -0.889 0 270)
			(size 1.016 1.27)
			(layers "B.Cu" "B.Mask" "B.Paste")
			(net "GND")
		)
	)
	(footprint ""
		(layer "B.Cu")
		(at 3.81 -64.837056 -90)
		(property "Reference" "PC40"
			(at 0 0 90)
			(layer "B.SilkS")
			(hide yes)
			(effects
				(font
					(size 1.27 1.27)
				)
				(justify mirror)
			)
		)
		(property "Value" ""
			(at 0 0 90)
			(layer "B.Fab")
			(effects
				(font
					(size 1.27 1.27)
				)
				(justify mirror)
			)
		)
		(duplicate_pad_numbers_are_jumpers no)
		(fp_line
			(start -0.7874 0.4064)
			(end 0.7874 0.4064)
			(stroke
				(width 0.1524)
				(type default)
			)
			(layer "B.SilkS")
		)
		(fp_line
			(start 0.7874 0.4064)
			(end 0.7874 -0.4064)
			(stroke
				(width 0.1524)
				(type default)
			)
			(layer "B.SilkS")
		)
		(fp_line
			(start -0.7874 -0.4064)
			(end -0.7874 0.4064)
			(stroke
				(width 0.1524)
				(type default)
			)
			(layer "B.SilkS")
		)
		(fp_line
			(start 0.7874 -0.4064)
			(end -0.7874 -0.4064)
			(stroke
				(width 0.1524)
				(type default)
			)
			(layer "B.SilkS")
		)
		(fp_line
			(start -0.67945 0.3048)
			(end -0.120396 0.3048)
			(stroke
				(width 0.1)
				(type default)
			)
			(layer "B.Fab")
		)
		(fp_line
			(start -0.120396 0.3048)
			(end -0.120396 0.2794)
			(stroke
				(width 0.1)
				(type default)
			)
			(layer "B.Fab")
		)
		(fp_line
			(start 0.12065 0.3048)
			(end 0.67945 0.3048)
			(stroke
				(width 0.1)
				(type default)
			)
			(layer "B.Fab")
		)
		(fp_line
			(start 0.67945 0.3048)
			(end 0.67945 -0.305054)
			(stroke
				(width 0.1)
				(type default)
			)
			(layer "B.Fab")
		)
		(fp_line
			(start -0.120396 0.2794)
			(end 0.12065 0.2794)
			(stroke
				(width 0.1)
				(type default)
			)
			(layer "B.Fab")
		)
		(fp_line
			(start 0.12065 0.2794)
			(end 0.12065 0.3048)
			(stroke
				(width 0.1)
				(type default)
			)
			(layer "B.Fab")
		)
		(fp_line
			(start -0.12065 -0.2794)
			(end -0.12065 -0.3048)
			(stroke
				(width 0.1)
				(type default)
			)
			(layer "B.Fab")
		)
		(fp_line
			(start 0.12065 -0.2794)
			(end -0.12065 -0.2794)
			(stroke
				(width 0.1)
				(type default)
			)
			(layer "B.Fab")
		)
		(fp_line
			(start -0.67945 -0.3048)
			(end -0.67945 0.3048)
			(stroke
				(width 0.1)
				(type default)
			)
			(layer "B.Fab")
		)
		(fp_line
			(start -0.12065 -0.3048)
			(end -0.67945 -0.3048)
			(stroke
				(width 0.1)
				(type default)
			)
			(layer "B.Fab")
		)
		(fp_line
			(start 0.12065 -0.305054)
			(end 0.12065 -0.2794)
			(stroke
				(width 0.1)
				(type default)
			)
			(layer "B.Fab")
		)
		(fp_line
			(start 0.67945 -0.305054)
			(end 0.12065 -0.305054)
			(stroke
				(width 0.1)
				(type default)
			)
			(layer "B.Fab")
		)
		(pad "1" smd circle
			(at 0.40005 0 90)
			(size 0 0)
			(layers "B.Cu" "B.Mask" "B.Paste")
			(net "FAN_4_SS")
		)
		(pad "2" smd circle
			(at -0.40005 0 90)
			(size 0 0)
			(layers "B.Cu" "B.Mask" "B.Paste")
			(net "GND")
		)
	)
	(footprint ""
		(layer "B.Cu")
		(at 16.2052 -93.529912 180)
		(property "Reference" "C2113"
			(at 0 0 0)
			(layer "B.SilkS")
			(hide yes)
			(effects
				(font
					(size 1.27 1.27)
				)
				(justify mirror)
			)
		)
		(property "Value" ""
			(at 0 0 0)
			(layer "B.Fab")
			(effects
				(font
					(size 1.27 1.27)
				)
				(justify mirror)
			)
		)
		(duplicate_pad_numbers_are_jumpers no)
		(fp_line
			(start 2.2098 0.9398)
			(end 2.2098 -0.9398)
			(stroke
				(width 0.1524)
				(type default)
			)
			(layer "B.SilkS")
		)
		(fp_line
			(start 2.2098 -0.9398)
			(end -2.2098 -0.9398)
			(stroke
				(width 0.1524)
				(type default)
			)
			(layer "B.SilkS")
		)
		(fp_line
			(start -2.2098 0.9398)
			(end 2.2098 0.9398)
			(stroke
				(width 0.1524)
				(type default)
			)
			(layer "B.SilkS")
		)
		(fp_line
			(start -2.2098 -0.9398)
			(end -2.2098 0.9398)
			(stroke
				(width 0.1524)
				(type default)
			)
			(layer "B.SilkS")
		)
		(fp_line
			(start 1.700022 0.899922)
			(end 1.700022 -0.899922)
			(stroke
				(width 0.1)
				(type default)
			)
			(layer "B.Fab")
		)
		(fp_line
			(start 1.700022 -0.899922)
			(end -1.700022 -0.899922)
			(stroke
				(width 0.1)
				(type default)
			)
			(layer "B.Fab")
		)
		(fp_line
			(start -1.700022 0.899922)
			(end 1.700022 0.899922)
			(stroke
				(width 0.1)
				(type default)
			)
			(layer "B.Fab")
		)
		(fp_line
			(start -1.700022 -0.899922)
			(end -1.700022 0.899922)
			(stroke
				(width 0.1)
				(type default)
			)
			(layer "B.Fab")
		)
		(pad "1" smd rect
			(at 1.4732 0 180)
			(size 1.1684 1.5748)
			(layers "B.Cu" "B.Mask" "B.Paste")
			(net "P52V_FAN_5")
		)
		(pad "2" smd rect
			(at -1.4732 0 180)
			(size 1.1684 1.5748)
			(layers "B.Cu" "B.Mask" "B.Paste")
			(net "GND")
		)
	)
	(footprint ""
		(layer "B.Cu")
		(at 9.922002 -166.755826 180)
		(property "Reference" "C51"
			(at 0 0 0)
			(layer "B.SilkS")
			(hide yes)
			(effects
				(font
					(size 1.27 1.27)
				)
				(justify mirror)
			)
		)
		(property "Value" ""
			(at 0 0 0)
			(layer "B.Fab")
			(effects
				(font
					(size 1.27 1.27)
				)
				(justify mirror)
			)
		)
		(duplicate_pad_numbers_are_jumpers no)
		(fp_line
			(start 0.7874 0.4064)
			(end 0.7874 -0.4064)
			(stroke
				(width 0.1524)
				(type default)
			)
			(layer "B.SilkS")
		)
		(fp_line
			(start 0.7874 -0.4064)
			(end -0.7874 -0.4064)
			(stroke
				(width 0.1524)
				(type default)
			)
			(layer "B.SilkS")
		)
		(fp_line
			(start -0.7874 0.4064)
			(end 0.7874 0.4064)
			(stroke
				(width 0.1524)
				(type default)
			)
			(layer "B.SilkS")
		)
		(fp_line
			(start -0.7874 -0.4064)
			(end -0.7874 0.4064)
			(stroke
				(width 0.1524)
				(type default)
			)
			(layer "B.SilkS")
		)
		(fp_line
			(start 0.67945 0.3048)
			(end 0.67945 -0.305054)
			(stroke
				(width 0.1)
				(type default)
			)
			(layer "B.Fab")
		)
		(fp_line
			(start 0.67945 -0.305054)
			(end 0.12065 -0.305054)
			(stroke
				(width 0.1)
				(type default)
			)
			(layer "B.Fab")
		)
		(fp_line
			(start 0.12065 0.3048)
			(end 0.67945 0.3048)
			(stroke
				(width 0.1)
				(type default)
			)
			(layer "B.Fab")
		)
		(fp_line
			(start 0.12065 0.2794)
			(end 0.12065 0.3048)
			(stroke
				(width 0.1)
				(type default)
			)
			(layer "B.Fab")
		)
		(fp_line
			(start 0.12065 -0.2794)
			(end -0.12065 -0.2794)
			(stroke
				(width 0.1)
				(type default)
			)
			(layer "B.Fab")
		)
		(fp_line
			(start 0.12065 -0.305054)
			(end 0.12065 -0.2794)
			(stroke
				(width 0.1)
				(type default)
			)
			(layer "B.Fab")
		)
		(fp_line
			(start -0.120396 0.3048)
			(end -0.120396 0.2794)
			(stroke
				(width 0.1)
				(type default)
			)
			(layer "B.Fab")
		)
		(fp_line
			(start -0.120396 0.2794)
			(end 0.12065 0.2794)
			(stroke
				(width 0.1)
				(type default)
			)
			(layer "B.Fab")
		)
		(fp_line
			(start -0.12065 -0.2794)
			(end -0.12065 -0.3048)
			(stroke
				(width 0.1)
				(type default)
			)
			(layer "B.Fab")
		)
		(fp_line
			(start -0.12065 -0.3048)
			(end -0.67945 -0.3048)
			(stroke
				(width 0.1)
				(type default)
			)
			(layer "B.Fab")
		)
		(fp_line
			(start -0.67945 0.3048)
			(end -0.120396 0.3048)
			(stroke
				(width 0.1)
				(type default)
			)
			(layer "B.Fab")
		)
		(fp_line
			(start -0.67945 -0.3048)
			(end -0.67945 0.3048)
			(stroke
				(width 0.1)
				(type default)
			)
			(layer "B.Fab")
		)
		(pad "1" smd circle
			(at 0.40005 0)
			(size 0 0)
			(layers "B.Cu" "B.Mask" "B.Paste")
			(net "P3V3_AUX")
		)
		(pad "2" smd circle
			(at -0.40005 0)
			(size 0 0)
			(layers "B.Cu" "B.Mask" "B.Paste")
			(net "GND")
		)
	)
)
